(kicad_pcb
	(version 20260206)
	(generator "pcbnew")
	(generator_version "10.0")
	(general
		(thickness 1.6)
		(legacy_teardrops no)
	)
	(paper "A4")
	(title_block
		(title "4HDD Backplane_Layout.brd")
		(comment 1 "Tioga Pass / footprints 35-42 of 97")
	)
	(layers
		(0 "F.Cu" signal "TOP")
		(4 "In1.Cu" signal "L2GND")
		(6 "In2.Cu" signal "L3")
		(8 "In3.Cu" signal "L4")
		(10 "In4.Cu" signal "L5GND")
		(2 "B.Cu" signal "BOTTOM")
		(9 "F.Adhes" user "F.Adhesive")
		(11 "B.Adhes" user "B.Adhesive")
		(13 "F.Paste" user "Package Geometry/Pastemask Top")
		(15 "B.Paste" user "Package Geometry/Pastemask Bottom")
		(5 "F.SilkS" user "Ref Des/Silkscreen Top")
		(7 "B.SilkS" user "Ref Des/Silkscreen Bottom")
		(1 "F.Mask" user "Board Geometry/Soldermask Top")
		(3 "B.Mask" user "Board Geometry/Soldermask Bottom")
		(17 "Dwgs.User" user "User.Drawings")
		(19 "Cmts.User" user "User.Comments")
		(21 "Eco1.User" user "User.Eco1")
		(23 "Eco2.User" user "User.Eco2")
		(25 "Edge.Cuts" user "Board Geometry/Outline")
		(27 "Margin" user)
		(31 "F.CrtYd" user "Package Geometry/Place Bound Top")
		(29 "B.CrtYd" user "Package Geometry/Place Bound Bottom")
		(35 "F.Fab" user "Ref Des/Assembly Top")
		(33 "B.Fab" user "Ref Des/Assembly Bottom")
	)
	(footprint ""
		(layer "F.Cu")
		(at 81.52511 -8.5852)
		(property "Reference" "R151"
			(at 0 0 0)
			(layer "F.SilkS")
			(hide yes)
			(effects
				(font
					(size 1.27 1.27)
				)
			)
		)
		(property "Value" "10KR2J-3-GP"
			(at 0.064008 -3.993896 0)
			(unlocked yes)
			(layer "F.Fab")
			(hide yes)
			(effects
				(font
					(size 1.016 1.016)
					(thickness 0.1524)
				)
			)
		)
		(property "Device Type" "R402H16"
			(at 0.064008 -5.517896 0)
			(unlocked yes)
			(layer "F.Fab")
			(hide yes)
			(effects
				(font
					(size 1.016 1.016)
					(thickness 0.1524)
				)
			)
		)
		(duplicate_pad_numbers_are_jumpers no)
		(fp_line
			(start -0.508 -0.9398)
			(end -0.508 0.9398)
			(stroke
				(width 0.1524)
				(type default)
			)
			(layer "F.SilkS")
		)
		(fp_line
			(start 0.508 -0.9398)
			(end -0.508 -0.9398)
			(stroke
				(width 0.1524)
				(type default)
			)
			(layer "F.SilkS")
		)
		(fp_rect
			(start -0.508 0.9398)
			(end 0.508 -0.9398)
			(stroke
				(width 0)
				(type default)
			)
			(fill no)
			(layer "F.CrtYd")
		)
		(fp_rect
			(start -0.508 0.9398)
			(end 0.508 -0.9398)
			(stroke
				(width 0)
				(type default)
			)
			(fill no)
			(layer "F.Fab")
		)
		(pad "1" smd custom
			(at 0 -0.4445)
			(size 0.1397 0.1397)
			(layers "F.Cu" "F.Mask" "F.Paste")
			(net "P3V3")
			(options
				(clearance outline)
				(anchor circle)
			)
			(primitives
				(gr_poly
					(pts
						(arc
							(start -0.1778 -0.2794)
							(mid -0.249642 -0.249642)
							(end -0.2794 -0.1778)
						)
						(arc
							(start -0.2794 0.1778)
							(mid -0.249642 0.249642)
							(end -0.1778 0.2794)
						)
						(arc
							(start 0.1778 0.2794)
							(mid 0.249642 0.249642)
							(end 0.2794 0.1778)
						)
						(arc
							(start 0.2794 -0.1778)
							(mid 0.249642 -0.249642)
							(end 0.1778 -0.2794)
						)
					)
					(width 0)
					(fill yes)
				)
			)
		)
		(pad "2" smd custom
			(at 0 0.4445)
			(size 0.1397 0.1397)
			(layers "F.Cu" "F.Mask" "F.Paste")
			(net "ENIN_P1")
			(options
				(clearance outline)
				(anchor circle)
			)
			(primitives
				(gr_poly
					(pts
						(arc
							(start -0.1778 -0.2794)
							(mid -0.249642 -0.249642)
							(end -0.2794 -0.1778)
						)
						(arc
							(start -0.2794 0.1778)
							(mid -0.249642 0.249642)
							(end -0.1778 0.2794)
						)
						(arc
							(start 0.1778 0.2794)
							(mid 0.249642 0.249642)
							(end 0.2794 0.1778)
						)
						(arc
							(start 0.2794 -0.1778)
							(mid 0.249642 -0.249642)
							(end 0.1778 -0.2794)
						)
					)
					(width 0)
					(fill yes)
				)
			)
		)
	)
	(footprint ""
		(layer "F.Cu")
		(at 77.724 -48.895 -90)
		(property "Reference" "C2"
			(at 0 0 270)
			(layer "F.SilkS")
			(hide yes)
			(effects
				(font
					(size 1.27 1.27)
				)
			)
		)
		(property "Value" "SC10U10V5KX-L1-GP"
			(at -0.0762 -6.1214 270)
			(unlocked yes)
			(layer "F.Fab")
			(hide yes)
			(effects
				(font
					(size 1.016 1.016)
					(thickness 0.1524)
				)
			)
		)
		(property "Device Type" "C805H58"
			(at -0.0762 -8.1534 270)
			(unlocked yes)
			(layer "F.Fab")
			(hide yes)
			(effects
				(font
					(size 1.016 1.016)
					(thickness 0.1524)
				)
			)
		)
		(duplicate_pad_numbers_are_jumpers no)
		(fp_line
			(start 0.635 0)
			(end -0.635 0)
			(stroke
				(width 0.508)
				(type default)
			)
			(layer "F.SilkS")
		)
		(fp_rect
			(start -0.9652 1.778)
			(end 0.9652 -1.778)
			(stroke
				(width 0)
				(type default)
			)
			(fill no)
			(layer "F.CrtYd")
		)
		(fp_poly
			(pts
				(xy -0.9652 -1.778) (xy 0.9652 -1.778) (xy 0.9652 1.778) (xy -0.9652 1.778)
			)
			(stroke
				(width 0)
				(type default)
			)
			(fill no)
			(layer "F.Fab")
		)
		(pad "1" smd rect
			(at 0 -0.9652 270)
			(size 1.397 1.143)
			(layers "F.Cu" "F.Mask" "F.Paste")
			(net "P5V_SW_R")
		)
		(pad "2" smd rect
			(at 0 0.9652 270)
			(size 1.397 1.143)
			(layers "F.Cu" "F.Mask" "F.Paste")
			(net "GND")
		)
	)
	(footprint ""
		(layer "F.Cu")
		(at 82.588608 -8.58393)
		(property "Reference" "R152"
			(at 0 0 0)
			(layer "F.SilkS")
			(hide yes)
			(effects
				(font
					(size 1.27 1.27)
				)
			)
		)
		(property "Value" "4K7R2J-2-GP"
			(at 0.064008 -3.993896 0)
			(unlocked yes)
			(layer "F.Fab")
			(hide yes)
			(effects
				(font
					(size 1.016 1.016)
					(thickness 0.1524)
				)
			)
		)
		(property "Device Type" "R402H16"
			(at 0.064008 -5.517896 0)
			(unlocked yes)
			(layer "F.Fab")
			(hide yes)
			(effects
				(font
					(size 1.016 1.016)
					(thickness 0.1524)
				)
			)
		)
		(duplicate_pad_numbers_are_jumpers no)
		(fp_line
			(start -0.508 -0.9398)
			(end -0.508 0.9398)
			(stroke
				(width 0.1524)
				(type default)
			)
			(layer "F.SilkS")
		)
		(fp_line
			(start 0.508 -0.9398)
			(end -0.508 -0.9398)
			(stroke
				(width 0.1524)
				(type default)
			)
			(layer "F.SilkS")
		)
		(fp_rect
			(start -0.508 0.9398)
			(end 0.508 -0.9398)
			(stroke
				(width 0)
				(type default)
			)
			(fill no)
			(layer "F.CrtYd")
		)
		(fp_rect
			(start -0.508 0.9398)
			(end 0.508 -0.9398)
			(stroke
				(width 0)
				(type default)
			)
			(fill no)
			(layer "F.Fab")
		)
		(pad "1" smd custom
			(at 0 -0.4445)
			(size 0.1397 0.1397)
			(layers "F.Cu" "F.Mask" "F.Paste")
			(net "P3V3")
			(options
				(clearance outline)
				(anchor circle)
			)
			(primitives
				(gr_poly
					(pts
						(arc
							(start -0.1778 -0.2794)
							(mid -0.249642 -0.249642)
							(end -0.2794 -0.1778)
						)
						(arc
							(start -0.2794 0.1778)
							(mid -0.249642 0.249642)
							(end -0.1778 0.2794)
						)
						(arc
							(start 0.1778 0.2794)
							(mid 0.249642 0.249642)
							(end 0.2794 0.1778)
						)
						(arc
							(start 0.2794 -0.1778)
							(mid 0.249642 -0.249642)
							(end 0.1778 -0.2794)
						)
					)
					(width 0)
					(fill yes)
				)
			)
		)
		(pad "2" smd custom
			(at 0 0.4445)
			(size 0.1397 0.1397)
			(layers "F.Cu" "F.Mask" "F.Paste")
			(net "PWR_EN_L_DELAY")
			(options
				(clearance outline)
				(anchor circle)
			)
			(primitives
				(gr_poly
					(pts
						(arc
							(start -0.1778 -0.2794)
							(mid -0.249642 -0.249642)
							(end -0.2794 -0.1778)
						)
						(arc
							(start -0.2794 0.1778)
							(mid -0.249642 0.249642)
							(end -0.1778 0.2794)
						)
						(arc
							(start 0.1778 0.2794)
							(mid 0.249642 0.249642)
							(end 0.2794 0.1778)
						)
						(arc
							(start 0.2794 -0.1778)
							(mid 0.249642 -0.249642)
							(end 0.1778 -0.2794)
						)
					)
					(width 0)
					(fill yes)
				)
			)
		)
	)
	(footprint ""
		(layer "F.Cu")
		(at 3.999992 -17.020032)
		(property "Reference" "H3"
			(at 0 0 0)
			(layer "F.SilkS")
			(hide yes)
			(effects
				(font
					(size 1.27 1.27)
				)
			)
		)
		(property "Value" "HOLET217B237R130-GP"
			(at -5.08 -0.4572 0)
			(unlocked yes)
			(layer "F.Fab")
			(hide yes)
			(effects
				(font
					(size 1.016 1.016)
					(thickness 0.1524)
				)
			)
		)
		(property "Device Type" "HOLET217B237R130"
			(at -5.08 -1.9812 0)
			(unlocked yes)
			(layer "F.Fab")
			(hide yes)
			(effects
				(font
					(size 1.016 1.016)
					(thickness 0.1524)
				)
			)
		)
		(duplicate_pad_numbers_are_jumpers no)
		(fp_poly
			(pts
				(arc
					(start 3.3147 0)
					(mid -3.3147 0)
					(end 3.3147 0)
				)
			)
			(stroke
				(width 0)
				(type default)
			)
			(fill no)
			(layer "B.CrtYd")
		)
		(fp_poly
			(pts
				(arc
					(start 3.0607 0)
					(mid -3.0607 0)
					(end 3.0607 0)
				)
			)
			(stroke
				(width 0)
				(type default)
			)
			(fill no)
			(layer "F.CrtYd")
		)
		(fp_poly
			(pts
				(arc
					(start 3.3147 0)
					(mid -3.3147 0)
					(end 3.3147 0)
				)
			)
			(stroke
				(width 0)
				(type default)
			)
			(fill no)
			(layer "B.Fab")
		)
		(fp_poly
			(pts
				(arc
					(start 3.0607 0)
					(mid -3.0607 0)
					(end 3.0607 0)
				)
			)
			(stroke
				(width 0)
				(type default)
			)
			(fill no)
			(layer "F.Fab")
		)
		(pad "1" thru_hole circle
			(at 0 0)
			(size 5.5118 5.5118)
			(drill 3.302)
			(layers "*.Cu" "*.Mask")
			(remove_unused_layers no)
			(net "GND")
			(clearance -0.5969)
			(thermal_gap 0.3048)
			(padstack
				(mode front_inner_back)
				(layer "Inner"
					(shape circle)
					(size 3.7084 3.7084)
					(clearance 0.3048)
				)
				(layer "B.Cu"
					(shape circle)
					(size 6.0198 6.0198)
					(clearance -0.8509)
				)
			)
		)
	)
	(footprint ""
		(layer "F.Cu")
		(at 50.45202 -20.793456 90)
		(property "Reference" "C17"
			(at 0 0 90)
			(layer "F.SilkS")
			(hide yes)
			(effects
				(font
					(size 1.27 1.27)
				)
			)
		)
		(property "Value" "SCD1U25V2KX-GP"
			(at 1.1811 -2.7051 90)
			(unlocked yes)
			(layer "F.Fab")
			(hide yes)
			(effects
				(font
					(size 1.016 1.016)
					(thickness 0.1524)
				)
			)
		)
		(property "Device Type" "C402H22"
			(at 1.1811 -4.2291 90)
			(unlocked yes)
			(layer "F.Fab")
			(hide yes)
			(effects
				(font
					(size 1.016 1.016)
					(thickness 0.1524)
				)
			)
		)
		(duplicate_pad_numbers_are_jumpers no)
		(fp_rect
			(start -0.4318 0.9525)
			(end 0.4318 -0.9525)
			(stroke
				(width 0)
				(type default)
			)
			(fill no)
			(layer "F.CrtYd")
		)
		(fp_rect
			(start -0.4318 0.9525)
			(end 0.4318 -0.9525)
			(stroke
				(width 0)
				(type default)
			)
			(fill no)
			(layer "F.Fab")
		)
		(pad "1" smd custom
			(at 0 -0.4445 90)
			(size 0.1524 0.1524)
			(layers "F.Cu" "F.Mask" "F.Paste")
			(net "P5V_SW_L")
			(options
				(clearance outline)
				(anchor circle)
			)
			(primitives
				(gr_poly
					(pts
						(arc
							(start 0.3048 -0.2032)
							(mid 0.275042 -0.275042)
							(end 0.2032 -0.3048)
						)
						(arc
							(start -0.2032 -0.3048)
							(mid -0.275042 -0.275042)
							(end -0.3048 -0.2032)
						)
						(arc
							(start -0.3048 0.2032)
							(mid -0.275042 0.275042)
							(end -0.2032 0.3048)
						)
						(arc
							(start 0.2032 0.3048)
							(mid 0.275042 0.275042)
							(end 0.3048 0.2032)
						)
					)
					(width 0)
					(fill yes)
				)
			)
		)
		(pad "2" smd custom
			(at 0 0.4445 90)
			(size 0.1524 0.1524)
			(layers "F.Cu" "F.Mask" "F.Paste")
			(net "GND")
			(options
				(clearance outline)
				(anchor circle)
			)
			(primitives
				(gr_poly
					(pts
						(arc
							(start 0.3048 -0.2032)
							(mid 0.275042 -0.275042)
							(end 0.2032 -0.3048)
						)
						(arc
							(start -0.2032 -0.3048)
							(mid -0.275042 -0.275042)
							(end -0.3048 -0.2032)
						)
						(arc
							(start -0.3048 0.2032)
							(mid -0.275042 0.275042)
							(end -0.2032 0.3048)
						)
						(arc
							(start 0.2032 0.3048)
							(mid 0.275042 0.275042)
							(end 0.3048 0.2032)
						)
					)
					(width 0)
					(fill yes)
				)
			)
		)
	)
	(footprint ""
		(layer "F.Cu")
		(at 82.998564 -50.779426 -90)
		(property "Reference" "R165"
			(at 0 0 270)
			(layer "F.SilkS")
			(hide yes)
			(effects
				(font
					(size 1.27 1.27)
				)
			)
		)
		(property "Value" "0R5J-5-GP"
			(at 0 -8.9535 270)
			(unlocked yes)
			(layer "F.Fab")
			(hide yes)
			(effects
				(font
					(size 1.27 1.016)
					(thickness 0.1524)
				)
			)
		)
		(property "Device Type" "R805H24"
			(at 0 -10.6299 270)
			(unlocked yes)
			(layer "F.Fab")
			(hide yes)
			(effects
				(font
					(size 1.27 1.016)
					(thickness 0.1524)
				)
			)
		)
		(duplicate_pad_numbers_are_jumpers no)
		(fp_line
			(start -0.889 1.7018)
			(end 0.889 1.7018)
			(stroke
				(width 0.1524)
				(type default)
			)
			(layer "F.SilkS")
		)
		(fp_line
			(start 0.889 1.7018)
			(end 0.889 -0.508)
			(stroke
				(width 0.1524)
				(type default)
			)
			(layer "F.SilkS")
		)
		(fp_line
			(start -0.889 0.0762)
			(end -0.889 1.7018)
			(stroke
				(width 0.1524)
				(type default)
			)
			(layer "F.SilkS")
		)
		(fp_line
			(start -0.889 -1.7018)
			(end -0.889 0.2794)
			(stroke
				(width 0.1524)
				(type default)
			)
			(layer "F.SilkS")
		)
		(fp_line
			(start 0.889 -1.7018)
			(end 0.889 -0.381)
			(stroke
				(width 0.1524)
				(type default)
			)
			(layer "F.SilkS")
		)
		(fp_line
			(start 0.889 -1.7018)
			(end -0.889 -1.7018)
			(stroke
				(width 0.1524)
				(type default)
			)
			(layer "F.SilkS")
		)
		(fp_poly
			(pts
				(xy 0.9652 -1.778) (xy 0.9652 1.778) (xy -0.9652 1.778) (xy -0.9652 -1.778)
			)
			(stroke
				(width 0)
				(type default)
			)
			(fill no)
			(layer "F.CrtYd")
		)
		(fp_rect
			(start -0.9652 1.778)
			(end 0.9652 -1.778)
			(stroke
				(width 0)
				(type default)
			)
			(fill no)
			(layer "F.Fab")
		)
		(pad "1" smd rect
			(at 0 -0.9652 270)
			(size 1.397 1.143)
			(layers "F.Cu" "F.Mask" "F.Paste")
			(net "P5V")
		)
		(pad "2" smd rect
			(at 0 0.9652 270)
			(size 1.397 1.143)
			(layers "F.Cu" "F.Mask" "F.Paste")
			(net "P5V_SW_R")
		)
	)
	(footprint ""
		(layer "F.Cu")
		(at 130.683 -40.259 -90)
		(property "Reference" "R5"
			(at 0 0 270)
			(layer "F.SilkS")
			(hide yes)
			(effects
				(font
					(size 1.27 1.27)
				)
			)
		)
		(property "Value" "10R3F-GP"
			(at -0.0254 -2.5146 270)
			(unlocked yes)
			(layer "F.Fab")
			(hide yes)
			(effects
				(font
					(size 1.016 1.016)
					(thickness 0.1524)
				)
			)
		)
		(property "Device Type" "R603H22"
			(at -0.0254 -4.0386 270)
			(unlocked yes)
			(layer "F.Fab")
			(hide yes)
			(effects
				(font
					(size 1.016 1.016)
					(thickness 0.1524)
				)
			)
		)
		(duplicate_pad_numbers_are_jumpers no)
		(fp_line
			(start -0.4826 0)
			(end -0.2032 0)
			(stroke
				(width 0.2032)
				(type default)
			)
			(layer "F.SilkS")
		)
		(fp_line
			(start 0.2032 0)
			(end 0.4826 0)
			(stroke
				(width 0.2032)
				(type default)
			)
			(layer "F.SilkS")
		)
		(fp_rect
			(start -0.5842 1.3335)
			(end 0.5842 -1.3335)
			(stroke
				(width 0)
				(type default)
			)
			(fill no)
			(layer "F.CrtYd")
		)
		(fp_rect
			(start -0.5842 1.3335)
			(end 0.5842 -1.3335)
			(stroke
				(width 0)
				(type default)
			)
			(fill no)
			(layer "F.Fab")
		)
		(pad "1" smd custom
			(at 0 -0.762 270)
			(size 0.2159 0.2159)
			(layers "F.Cu" "F.Mask" "F.Paste")
			(net "P12V_SW_R")
			(options
				(clearance outline)
				(anchor circle)
			)
			(primitives
				(gr_poly
					(pts
						(arc
							(start -0.3302 -0.4318)
							(mid -0.402042 -0.402042)
							(end -0.4318 -0.3302)
						)
						(arc
							(start -0.4318 0.3302)
							(mid -0.402042 0.402042)
							(end -0.3302 0.4318)
						)
						(arc
							(start 0.3302 0.4318)
							(mid 0.402042 0.402042)
							(end 0.4318 0.3302)
						)
						(arc
							(start 0.4318 -0.3302)
							(mid 0.402042 -0.402042)
							(end 0.3302 -0.4318)
						)
					)
					(width 0)
					(fill yes)
				)
			)
		)
		(pad "2" smd custom
			(at 0 0.762 270)
			(size 0.2159 0.2159)
			(layers "F.Cu" "F.Mask" "F.Paste")
			(net "12V_PRE_1")
			(options
				(clearance outline)
				(anchor circle)
			)
			(primitives
				(gr_poly
					(pts
						(arc
							(start -0.3302 -0.4318)
							(mid -0.402042 -0.402042)
							(end -0.4318 -0.3302)
						)
						(arc
							(start -0.4318 0.3302)
							(mid -0.402042 0.402042)
							(end -0.3302 0.4318)
						)
						(arc
							(start 0.3302 0.4318)
							(mid 0.402042 0.402042)
							(end 0.4318 0.3302)
						)
						(arc
							(start 0.4318 -0.3302)
							(mid 0.402042 -0.402042)
							(end 0.3302 -0.4318)
						)
					)
					(width 0)
					(fill yes)
				)
			)
		)
	)
	(footprint ""
		(layer "F.Cu")
		(at 84.112354 -38.56736)
		(property "Reference" "C29"
			(at 0 0 0)
			(layer "F.SilkS")
			(hide yes)
			(effects
				(font
					(size 1.27 1.27)
				)
			)
		)
		(property "Value" "SCD1U25V2KX-2-GP"
			(at 1.1811 -2.7051 0)
			(unlocked yes)
			(layer "F.Fab")
			(hide yes)
			(effects
				(font
					(size 1.016 1.016)
					(thickness 0.1524)
				)
			)
		)
		(property "Device Type" "C402H22"
			(at 1.1811 -4.2291 0)
			(unlocked yes)
			(layer "F.Fab")
			(hide yes)
			(effects
				(font
					(size 1.016 1.016)
					(thickness 0.1524)
				)
			)
		)
		(duplicate_pad_numbers_are_jumpers no)
		(fp_rect
			(start -0.4318 0.9525)
			(end 0.4318 -0.9525)
			(stroke
				(width 0)
				(type default)
			)
			(fill no)
			(layer "F.CrtYd")
		)
		(fp_rect
			(start -0.4318 0.9525)
			(end 0.4318 -0.9525)
			(stroke
				(width 0)
				(type default)
			)
			(fill no)
			(layer "F.Fab")
		)
		(pad "1" smd custom
			(at 0 -0.4445)
			(size 0.1524 0.1524)
			(layers "F.Cu" "F.Mask" "F.Paste")
			(net "P12V")
			(options
				(clearance outline)
				(anchor circle)
			)
			(primitives
				(gr_poly
					(pts
						(arc
							(start 0.3048 -0.2032)
							(mid 0.275042 -0.275042)
							(end 0.2032 -0.3048)
						)
						(arc
							(start -0.2032 -0.3048)
							(mid -0.275042 -0.275042)
							(end -0.3048 -0.2032)
						)
						(arc
							(start -0.3048 0.2032)
							(mid -0.275042 0.275042)
							(end -0.2032 0.3048)
						)
						(arc
							(start 0.2032 0.3048)
							(mid 0.275042 0.275042)
							(end 0.3048 0.2032)
						)
					)
					(width 0)
					(fill yes)
				)
			)
		)
		(pad "2" smd custom
			(at 0 0.4445)
			(size 0.1524 0.1524)
			(layers "F.Cu" "F.Mask" "F.Paste")
			(net "SW_SW_R_N_0")
			(options
				(clearance outline)
				(anchor circle)
			)
			(primitives
				(gr_poly
					(pts
						(arc
							(start 0.3048 -0.2032)
							(mid 0.275042 -0.275042)
							(end 0.2032 -0.3048)
						)
						(arc
							(start -0.2032 -0.3048)
							(mid -0.275042 -0.275042)
							(end -0.3048 -0.2032)
						)
						(arc
							(start -0.3048 0.2032)
							(mid -0.275042 0.275042)
							(end -0.2032 0.3048)
						)
						(arc
							(start 0.2032 0.3048)
							(mid 0.275042 0.275042)
							(end 0.3048 0.2032)
						)
					)
					(width 0)
					(fill yes)
				)
			)
		)
	)
)
